# BASEBOARD_FAB2 (Tioga Pass) — schematic netlist excerpt (pin names and nets, part order shuffled) for the footprints in the layout excerpt that follows; sources: Cadence DE-HDL packaged netlist, KiCad conversion of Wiwynn_Tioga_Pass_MB.brd

U9G1  GTL2014  IC  pkg SM  page 152
  DIR  = PD_DIR_2
  B0  = H_CPU1_MEMKLM_MEMHOT_G_R_N
  B1  = H_CPU1_MEMGHJ_MEMHOT_G_R_N
  VREF  = P0V7_GTL2014_2
  B2  = H_CPU0_MEMDEF_MEMHOT_G_R_N
  B3  = H_CPU0_MEMABC_MEMHOT_G_R_N
  GND(0)  = GND
  GND(1)  = GND
  A3  = H_CPU0_ABC_MEMHOT_LVT3_R_N
  A2  = H_CPU0_DEF_MEMHOT_LVT3_R_N
  GND(2)  = GND
  A1  = H_CPU1_GHJ_MEMHOT_LVT3_R_N
  A0  = H_CPU1_KLM_MEMHOT_LVT3_R_N
  VCC  = P3V3

R25W129  RES  4.75K 1% CHIP  pkg 0402  page 146 : A = P3V3 ; B = I2C_BMC_VGA_DDC_SCL

(kicad_pcb
	(version 20260206)
	(generator "pcbnew")
	(generator_version "10.0")
	(general
		(thickness 1.6)
		(legacy_teardrops no)
	)
	(paper "A4")
	(title_block
		(title "Wiwynn_Tioga_Pass_MB.brd")
		(comment 1 "Tioga Pass / footprints 3392-3393 of 4770")
	)
	(layers
		(0 "F.Cu" signal "TOP")
		(4 "In1.Cu" signal "L2GND")
		(6 "In2.Cu" signal "L3")
		(8 "In3.Cu" signal "L4GND")
		(10 "In4.Cu" signal "L5")
		(12 "In5.Cu" signal "L6GND")
		(14 "In6.Cu" signal "L7VCC")
		(16 "In7.Cu" signal "L8VCC")
		(18 "In8.Cu" signal "L9GND")
		(20 "In9.Cu" signal "L10")
		(22 "In10.Cu" signal "L11GND")
		(24 "In11.Cu" signal "L12")
		(26 "In12.Cu" signal "L13GND")
		(2 "B.Cu" signal "BOTTOM")
		(9 "F.Adhes" user "F.Adhesive")
		(11 "B.Adhes" user "B.Adhesive")
		(13 "F.Paste" user "Package Geometry/Pastemask Top")
		(15 "B.Paste" user "Package Geometry/Pastemask Bottom")
		(5 "F.SilkS" user "Ref Des/Silkscreen Top")
		(7 "B.SilkS" user "Ref Des/Silkscreen Bottom")
		(1 "F.Mask" user "Board Geometry/Soldermask Top")
		(3 "B.Mask" user "Board Geometry/Soldermask Bottom")
		(17 "Dwgs.User" user "User.Drawings")
		(19 "Cmts.User" user "User.Comments")
		(21 "Eco1.User" user "User.Eco1")
		(23 "Eco2.User" user "User.Eco2")
		(25 "Edge.Cuts" user "Board Geometry/Outline")
		(27 "Margin" user)
		(31 "F.CrtYd" user "Package Geometry/Place Bound Top")
		(29 "B.CrtYd" user "Package Geometry/Place Bound Bottom")
		(35 "F.Fab" user "Ref Des/Assembly Top")
		(33 "B.Fab" user "Ref Des/Assembly Bottom")
	)
	(footprint ""
		(layer "B.Cu")
		(at 438.5945 -15.92072)
		(property "Reference" "U9G1"
			(at -5.64388 -0.89027 0)
			(unlocked yes)
			(layer "B.SilkS")
			(effects
				(font
					(size 0.7874 0.5842)
					(thickness 0.1524)
				)
				(justify left mirror)
			)
		)
		(property "Value" ""
			(at 0 0 0)
			(layer "B.Fab")
			(effects
				(font
					(size 1.27 1.27)
				)
				(justify mirror)
			)
		)
		(duplicate_pad_numbers_are_jumpers no)
		(fp_line
			(start -4.4323 -0.64008)
			(end -4.4323 4.52628)
			(stroke
				(width 0.1524)
				(type default)
			)
			(layer "B.SilkS")
		)
		(fp_line
			(start -4.4323 4.52628)
			(end -1.5367 4.52628)
			(stroke
				(width 0.1524)
				(type default)
			)
			(layer "B.SilkS")
		)
		(fp_line
			(start -3.302 0.49022)
			(end -3.302 -0.64008)
			(stroke
				(width 0.1524)
				(type default)
			)
			(layer "B.SilkS")
		)
		(fp_line
			(start -2.667 -0.64008)
			(end -2.667 0.49022)
			(stroke
				(width 0.1524)
				(type default)
			)
			(layer "B.SilkS")
		)
		(fp_line
			(start -2.667 0.49022)
			(end -3.302 0.49022)
			(stroke
				(width 0.1524)
				(type default)
			)
			(layer "B.SilkS")
		)
		(fp_line
			(start -1.5367 -0.64008)
			(end -4.4323 -0.64008)
			(stroke
				(width 0.1524)
				(type default)
			)
			(layer "B.SilkS")
		)
		(fp_line
			(start -1.5367 4.52628)
			(end -1.5367 -0.64008)
			(stroke
				(width 0.1524)
				(type default)
			)
			(layer "B.SilkS")
		)
		(fp_circle
			(center 1.296162 -0.6731)
			(end 1.423162 -0.6731)
			(stroke
				(width 0.254)
				(type default)
			)
			(fill no)
			(layer "B.SilkS")
		)
		(fp_poly
			(pts
				(xy -0.7366 4.54152) (xy -0.7366 -0.64008) (xy -4.7244 -0.64008) (xy -5.2324 -0.64008) (xy -5.2324 4.54152)
				(xy -4.7244 4.54152)
			)
			(stroke
				(width 0)
				(type default)
			)
			(fill no)
			(layer "B.CrtYd")
		)
		(fp_line
			(start -5.2324 -0.64008)
			(end -5.2324 4.54152)
			(stroke
				(width 0.1)
				(type default)
			)
			(layer "B.Fab")
		)
		(fp_line
			(start -5.2324 4.54152)
			(end -0.7366 4.54152)
			(stroke
				(width 0.1)
				(type default)
			)
			(layer "B.Fab")
		)
		(fp_line
			(start -3.302 0.49022)
			(end -3.302 -0.64008)
			(stroke
				(width 0.1)
				(type default)
			)
			(layer "B.Fab")
		)
		(fp_line
			(start -2.667 -0.64008)
			(end -2.667 0.49022)
			(stroke
				(width 0.1)
				(type default)
			)
			(layer "B.Fab")
		)
		(fp_line
			(start -2.667 0.49022)
			(end -3.302 0.49022)
			(stroke
				(width 0.1)
				(type default)
			)
			(layer "B.Fab")
		)
		(fp_line
			(start -0.7366 -0.64008)
			(end -5.2324 -0.64008)
			(stroke
				(width 0.1)
				(type default)
			)
			(layer "B.Fab")
		)
		(fp_line
			(start -0.7366 4.54152)
			(end -0.7366 -0.64008)
			(stroke
				(width 0.1)
				(type default)
			)
			(layer "B.Fab")
		)
		(fp_circle
			(center 1.612138 -0.684784)
			(end 1.739138 -0.684784)
			(stroke
				(width 0.254)
				(type default)
			)
			(fill no)
			(layer "B.Fab")
		)
		(pad "1" smd rect
			(at 0 0 180)
			(size 2.159 0.381)
			(layers "B.Cu" "B.Mask" "B.Paste")
			(net "PD_DIR_2")
		)
		(pad "2" smd rect
			(at 0 0.65024 180)
			(size 2.159 0.381)
			(layers "B.Cu" "B.Mask" "B.Paste")
			(net "H_CPU1_MEMKLM_MEMHOT_G_R_N")
		)
		(pad "3" smd rect
			(at 0 1.30048 180)
			(size 2.159 0.381)
			(layers "B.Cu" "B.Mask" "B.Paste")
			(net "H_CPU1_MEMGHJ_MEMHOT_G_R_N")
		)
		(pad "4" smd rect
			(at 0 1.95072 180)
			(size 2.159 0.381)
			(layers "B.Cu" "B.Mask" "B.Paste")
			(net "P0V7_GTL2014_2")
		)
		(pad "5" smd rect
			(at 0 2.60096 180)
			(size 2.159 0.381)
			(layers "B.Cu" "B.Mask" "B.Paste")
			(net "H_CPU0_MEMDEF_MEMHOT_G_R_N")
		)
		(pad "6" smd rect
			(at 0 3.2512 180)
			(size 2.159 0.381)
			(layers "B.Cu" "B.Mask" "B.Paste")
			(net "H_CPU0_MEMABC_MEMHOT_G_R_N")
		)
		(pad "7" smd rect
			(at 0 3.90144 180)
			(size 2.159 0.381)
			(layers "B.Cu" "B.Mask" "B.Paste")
			(net "GND")
		)
		(pad "8" smd rect
			(at -5.969 3.90144 180)
			(size 2.159 0.381)
			(layers "B.Cu" "B.Mask" "B.Paste")
			(net "GND")
		)
		(pad "9" smd rect
			(at -5.969 3.2512 180)
			(size 2.159 0.381)
			(layers "B.Cu" "B.Mask" "B.Paste")
			(net "H_CPU0_ABC_MEMHOT_LVT3_R_N")
		)
		(pad "10" smd rect
			(at -5.969 2.60096 180)
			(size 2.159 0.381)
			(layers "B.Cu" "B.Mask" "B.Paste")
			(net "H_CPU0_DEF_MEMHOT_LVT3_R_N")
		)
		(pad "11" smd rect
			(at -5.969 1.95072 180)
			(size 2.159 0.381)
			(layers "B.Cu" "B.Mask" "B.Paste")
			(net "GND")
		)
		(pad "12" smd rect
			(at -5.969 1.30048 180)
			(size 2.159 0.381)
			(layers "B.Cu" "B.Mask" "B.Paste")
			(net "H_CPU1_GHJ_MEMHOT_LVT3_R_N")
		)
		(pad "13" smd rect
			(at -5.969 0.65024 180)
			(size 2.159 0.381)
			(layers "B.Cu" "B.Mask" "B.Paste")
			(net "H_CPU1_KLM_MEMHOT_LVT3_R_N")
		)
		(pad "14" smd rect
			(at -5.969 0 180)
			(size 2.159 0.381)
			(layers "B.Cu" "B.Mask" "B.Paste")
			(net "P3V3")
		)
	)
	(footprint ""
		(layer "B.Cu")
		(at 428.3075 -21.844 -90)
		(property "Reference" "R25W129"
			(at 0.8382 -0.67818 270)
			(unlocked yes)
			(layer "B.SilkS")
			(effects
				(font
					(size 0.4064 0.254)
					(thickness 0.1524)
				)
				(justify left mirror)
			)
		)
		(property "Value" ""
			(at 0 0 90)
			(layer "B.Fab")
			(effects
				(font
					(size 1.27 1.27)
				)
				(justify mirror)
			)
		)
		(duplicate_pad_numbers_are_jumpers no)
		(fp_poly
			(pts
				(xy 0.2794 -0.1016) (xy -0.2794 -0.1016) (xy -0.2794 0.9906) (xy 0.2794 0.9906)
			)
			(stroke
				(width 0)
				(type default)
			)
			(fill no)
			(layer "B.CrtYd")
		)
		(fp_line
			(start -0.2794 0.9906)
			(end -0.2794 -0.1016)
			(stroke
				(width 0.1)
				(type default)
			)
			(layer "B.Fab")
		)
		(fp_line
			(start 0.2794 0.9906)
			(end -0.2794 0.9906)
			(stroke
				(width 0.1)
				(type default)
			)
			(layer "B.Fab")
		)
		(fp_line
			(start -0.2794 -0.1016)
			(end 0.2794 -0.1016)
			(stroke
				(width 0.1)
				(type default)
			)
			(layer "B.Fab")
		)
		(fp_line
			(start 0.2794 -0.1016)
			(end 0.2794 0.9906)
			(stroke
				(width 0.1)
				(type default)
			)
			(layer "B.Fab")
		)
		(pad "1" smd rect
			(at 0 0 90)
			(size 0.508 0.508)
			(layers "B.Cu" "B.Mask" "B.Paste")
			(net "P3V3")
		)
		(pad "2" smd rect
			(at 0 0.889 90)
			(size 0.508 0.508)
			(layers "B.Cu" "B.Mask" "B.Paste")
			(net "I2C_BMC_VGA_DDC_SCL")
		)
		(zone
			(layer "B.Cu")
			(hatch none 0.5)
			(connect_pads
				(clearance 0)
			)
			(min_thickness 0.25)
			(keepout
				(tracks not_allowed)
				(vias allowed)
				(pads allowed)
				(copperpour not_allowed)
				(footprints allowed)
			)
			(placement
				(enabled no)
				(sheetname "")
			)
			(fill
				(thermal_gap 0.5)
				(thermal_bridge_width 0.5)
				(island_removal_mode 0)
			)
			(polygon
				(pts
					(xy 427.6725 -21.59) (xy 427.6725 -22.098) (xy 428.0535 -22.098) (xy 428.0535 -21.59)
				)
			)
		)
		(zone
			(layer "B.Cu")
			(hatch none 0.5)
			(connect_pads
				(clearance 0)
			)
			(min_thickness 0.25)
			(keepout
				(tracks allowed)
				(vias not_allowed)
				(pads allowed)
				(copperpour not_allowed)
				(footprints allowed)
			)
			(placement
				(enabled no)
				(sheetname "")
			)
			(fill
				(thermal_gap 0.5)
				(thermal_bridge_width 0.5)
				(island_removal_mode 0)
			)
			(polygon
				(pts
					(xy 428.0535 -21.59) (xy 428.0535 -22.098) (xy 427.6725 -22.098) (xy 427.6725 -21.59)
				)
			)
		)
	)
)
